(kicad_pcb
	(version 20260206)
	(generator "pcbnew")
	(generator_version "10.0")
	(general
		(thickness 1.6)
		(legacy_teardrops no)
	)
	(paper "A4")
	(title_block
		(title "01162023_DA0F0TEBIF0_F0T_Expander_BD_F_brd_V02_OCP.brd")
		(comment 1 "Grand Teton / footprints 2486-2492 of 9728")
	)
	(layers
		(0 "F.Cu" signal "TOP")
		(4 "In1.Cu" signal "GND")
		(6 "In2.Cu" signal "VCC")
		(8 "In3.Cu" signal "VCC1")
		(10 "In4.Cu" signal "GND1")
		(12 "In5.Cu" signal "IN1")
		(14 "In6.Cu" signal "GND2")
		(16 "In7.Cu" signal "IN2")
		(18 "In8.Cu" signal "GND3")
		(20 "In9.Cu" signal "IN3")
		(22 "In10.Cu" signal "GND4")
		(24 "In11.Cu" signal "IN4")
		(26 "In12.Cu" signal "GND5")
		(28 "In13.Cu" signal "IN5")
		(30 "In14.Cu" signal "GND6")
		(32 "In15.Cu" signal "IN6")
		(34 "In16.Cu" signal "GND7")
		(2 "B.Cu" signal "BOTTOM")
		(9 "F.Adhes" user "F.Adhesive")
		(11 "B.Adhes" user "B.Adhesive")
		(13 "F.Paste" user "Package Geometry/Pastemask Top")
		(15 "B.Paste" user "Package Geometry/Pastemask Bottom")
		(5 "F.SilkS" user "Ref Des/Silkscreen Top")
		(7 "B.SilkS" user "Ref Des/Silkscreen Bottom")
		(1 "F.Mask" user "Board Geometry/Soldermask Top")
		(3 "B.Mask" user "Board Geometry/Soldermask Bottom")
		(17 "Dwgs.User" user "User.Drawings")
		(19 "Cmts.User" user "User.Comments")
		(21 "Eco1.User" user "User.Eco1")
		(23 "Eco2.User" user "User.Eco2")
		(25 "Edge.Cuts" user "Board Geometry/Outline")
		(27 "Margin" user)
		(31 "F.CrtYd" user "Package Geometry/Place Bound Top")
		(29 "B.CrtYd" user "Package Geometry/Place Bound Bottom")
		(35 "F.Fab" user "Ref Des/Assembly Top")
		(33 "B.Fab" user "Ref Des/Assembly Bottom")
	)
	(footprint ""
		(layer "F.Cu")
		(at 374.910604 -18.61439 90)
		(property "Reference" "U138"
			(at -1.39319 2.280666 90)
			(unlocked yes)
			(layer "F.SilkS")
			(effects
				(font
					(size 0.7874 0.5842)
					(thickness 0.1524)
				)
				(justify left)
			)
		)
		(property "Value" ""
			(at 0 0 90)
			(layer "F.Fab")
			(effects
				(font
					(size 1.27 1.27)
				)
			)
		)
		(duplicate_pad_numbers_are_jumpers no)
		(fp_line
			(start 1.463548 -1.549908)
			(end 1.463548 1.549908)
			(stroke
				(width 0.1524)
				(type default)
			)
			(layer "F.SilkS")
		)
		(fp_line
			(start 0.762 -1.549908)
			(end 1.463548 -1.549908)
			(stroke
				(width 0.1524)
				(type default)
			)
			(layer "F.SilkS")
		)
		(fp_line
			(start -0.787908 -1.549908)
			(end 0 -0.762)
			(stroke
				(width 0.1524)
				(type default)
			)
			(layer "F.SilkS")
		)
		(fp_line
			(start -1.463548 -1.549908)
			(end -0.787908 -1.549908)
			(stroke
				(width 0.1524)
				(type default)
			)
			(layer "F.SilkS")
		)
		(fp_line
			(start 0 -0.762)
			(end 0.762 -1.549908)
			(stroke
				(width 0.1524)
				(type default)
			)
			(layer "F.SilkS")
		)
		(fp_line
			(start 1.463548 1.549908)
			(end -1.463548 1.549908)
			(stroke
				(width 0.1524)
				(type default)
			)
			(layer "F.SilkS")
		)
		(fp_line
			(start -1.463548 1.549908)
			(end -1.463548 -1.549908)
			(stroke
				(width 0.1524)
				(type default)
			)
			(layer "F.SilkS")
		)
		(fp_poly
			(pts
				(xy -3.4798 -1.359916) (xy -2.86004 -1.050036) (xy -3.4798 -0.740156)
			)
			(stroke
				(width 0)
				(type default)
			)
			(fill yes)
			(layer "F.SilkS")
		)
		(fp_line
			(start 1.549908 -1.549908)
			(end 1.549908 1.549908)
			(stroke
				(width 0.1)
				(type default)
			)
			(layer "F.Fab")
		)
		(fp_line
			(start -1.549908 -1.549908)
			(end 1.549908 -1.549908)
			(stroke
				(width 0.1)
				(type default)
			)
			(layer "F.Fab")
		)
		(fp_line
			(start 1.549908 1.549908)
			(end -1.549908 1.549908)
			(stroke
				(width 0.1)
				(type default)
			)
			(layer "F.Fab")
		)
		(fp_line
			(start -1.549908 1.549908)
			(end -1.549908 -1.549908)
			(stroke
				(width 0.1)
				(type default)
			)
			(layer "F.Fab")
		)
		(fp_poly
			(pts
				(xy -3.4798 -1.359916) (xy -2.86004 -1.050036) (xy -3.4798 -0.740156)
			)
			(stroke
				(width 0)
				(type default)
			)
			(fill yes)
			(layer "F.Fab")
		)
		(pad "1" smd rect
			(at -2.175002 -1.050036 180)
			(size 0.6096 1.1684)
			(layers "F.Cu" "F.Mask" "F.Paste")
			(net "P3V3_SSD12")
		)
		(pad "2" smd rect
			(at -2.175002 -0.32512 180)
			(size 0.4318 1.1684)
			(layers "F.Cu" "F.Mask" "F.Paste")
			(net "SMB_ISO_SSD12_SCL")
		)
		(pad "3" smd rect
			(at -2.175002 0.32512 180)
			(size 0.4318 1.1684)
			(layers "F.Cu" "F.Mask" "F.Paste")
			(net "SMB_ISO_SSD12_SDA")
		)
		(pad "4" smd rect
			(at -2.175002 1.050036 180)
			(size 0.6096 1.1684)
			(layers "F.Cu" "F.Mask" "F.Paste")
			(net "GND")
		)
		(pad "5" smd rect
			(at 2.175002 1.050036 180)
			(size 0.6096 1.1684)
			(layers "F.Cu" "F.Mask" "F.Paste")
			(net "SMB_SSD12_ISO_EN")
		)
		(pad "6" smd rect
			(at 2.175002 0.32512 180)
			(size 0.4318 1.1684)
			(layers "F.Cu" "F.Mask" "F.Paste")
			(net "SMB_BIC_I2C9_MUX1_SSD12_R_SDA")
		)
		(pad "7" smd rect
			(at 2.175002 -0.32512 180)
			(size 0.4318 1.1684)
			(layers "F.Cu" "F.Mask" "F.Paste")
			(net "SMB_BIC_I2C9_MUX1_SSD12_R_SCL")
		)
		(pad "8" smd rect
			(at 2.175002 -1.050036 180)
			(size 0.6096 1.1684)
			(layers "F.Cu" "F.Mask" "F.Paste")
			(net "P3V3_AUX")
		)
	)
	(footprint ""
		(layer "F.Cu")
		(at 145.239486 -390.398254 -90)
		(property "Reference" "R1846"
			(at 0 0 270)
			(layer "F.SilkS")
			(hide yes)
			(effects
				(font
					(size 1.27 1.27)
				)
			)
		)
		(property "Value" ""
			(at 0 0 270)
			(layer "F.Fab")
			(effects
				(font
					(size 1.27 1.27)
				)
			)
		)
		(duplicate_pad_numbers_are_jumpers no)
		(fp_line
			(start -0.7874 0.4064)
			(end -0.7874 -0.4064)
			(stroke
				(width 0.1524)
				(type default)
			)
			(layer "F.SilkS")
		)
		(fp_line
			(start 0.7874 0.4064)
			(end -0.7874 0.4064)
			(stroke
				(width 0.1524)
				(type default)
			)
			(layer "F.SilkS")
		)
		(fp_line
			(start -0.7874 -0.4064)
			(end 0.7874 -0.4064)
			(stroke
				(width 0.1524)
				(type default)
			)
			(layer "F.SilkS")
		)
		(fp_line
			(start 0.7874 -0.4064)
			(end 0.7874 0.4064)
			(stroke
				(width 0.1524)
				(type default)
			)
			(layer "F.SilkS")
		)
		(fp_line
			(start -0.67945 0.3048)
			(end -0.67945 -0.305054)
			(stroke
				(width 0.1)
				(type default)
			)
			(layer "F.Fab")
		)
		(fp_line
			(start -0.12065 0.3048)
			(end -0.67945 0.3048)
			(stroke
				(width 0.1)
				(type default)
			)
			(layer "F.Fab")
		)
		(fp_line
			(start 0.120396 0.3048)
			(end 0.120396 0.2794)
			(stroke
				(width 0.1)
				(type default)
			)
			(layer "F.Fab")
		)
		(fp_line
			(start 0.67945 0.3048)
			(end 0.120396 0.3048)
			(stroke
				(width 0.1)
				(type default)
			)
			(layer "F.Fab")
		)
		(fp_line
			(start -0.12065 0.2794)
			(end -0.12065 0.3048)
			(stroke
				(width 0.1)
				(type default)
			)
			(layer "F.Fab")
		)
		(fp_line
			(start 0.120396 0.2794)
			(end -0.12065 0.2794)
			(stroke
				(width 0.1)
				(type default)
			)
			(layer "F.Fab")
		)
		(fp_line
			(start -0.12065 -0.2794)
			(end 0.12065 -0.2794)
			(stroke
				(width 0.1)
				(type default)
			)
			(layer "F.Fab")
		)
		(fp_line
			(start 0.12065 -0.2794)
			(end 0.12065 -0.3048)
			(stroke
				(width 0.1)
				(type default)
			)
			(layer "F.Fab")
		)
		(fp_line
			(start 0.12065 -0.3048)
			(end 0.67945 -0.3048)
			(stroke
				(width 0.1)
				(type default)
			)
			(layer "F.Fab")
		)
		(fp_line
			(start 0.67945 -0.3048)
			(end 0.67945 0.3048)
			(stroke
				(width 0.1)
				(type default)
			)
			(layer "F.Fab")
		)
		(fp_line
			(start -0.67945 -0.305054)
			(end -0.12065 -0.305054)
			(stroke
				(width 0.1)
				(type default)
			)
			(layer "F.Fab")
		)
		(fp_line
			(start -0.12065 -0.305054)
			(end -0.12065 -0.2794)
			(stroke
				(width 0.1)
				(type default)
			)
			(layer "F.Fab")
		)
		(pad "1" smd circle
			(at -0.40005 0 270)
			(size 0 0)
			(layers "F.Cu" "F.Mask" "F.Paste")
			(net "SMB_GPU1_ALERT_R_N")
		)
		(pad "2" smd circle
			(at 0.40005 0 270)
			(size 0 0)
			(layers "F.Cu" "F.Mask" "F.Paste")
			(net "SMB_GPU1_ALERT_N")
		)
	)
	(footprint ""
		(layer "F.Cu")
		(at 327.471278 -121.291858)
		(property "Reference" "PU49"
			(at -1.010412 2.700528 0)
			(unlocked yes)
			(layer "F.SilkS")
			(effects
				(font
					(size 0.7874 0.5842)
					(thickness 0.1524)
				)
				(justify left)
			)
		)
		(property "Value" ""
			(at 0 0 0)
			(layer "F.Fab")
			(effects
				(font
					(size 1.27 1.27)
				)
			)
		)
		(duplicate_pad_numbers_are_jumpers no)
		(fp_line
			(start -1.943608 -1.549908)
			(end 1.943608 -1.549908)
			(stroke
				(width 0.1524)
				(type default)
			)
			(layer "F.SilkS")
		)
		(fp_line
			(start -1.943608 1.549908)
			(end -1.943608 -1.549908)
			(stroke
				(width 0.1524)
				(type default)
			)
			(layer "F.SilkS")
		)
		(fp_line
			(start 1.943608 -1.549908)
			(end 1.943608 1.549908)
			(stroke
				(width 0.1524)
				(type default)
			)
			(layer "F.SilkS")
		)
		(fp_line
			(start 1.943608 1.549908)
			(end -1.943608 1.549908)
			(stroke
				(width 0.1524)
				(type default)
			)
			(layer "F.SilkS")
		)
		(fp_poly
			(pts
				(xy -2.019808 -1.549908) (xy -1.257808 -1.549908) (xy -1.257808 -1.880108) (xy -2.019808 -1.880108)
			)
			(stroke
				(width 0)
				(type default)
			)
			(fill yes)
			(layer "F.SilkS")
		)
		(fp_line
			(start -1.549908 -1.549908)
			(end 1.549908 -1.549908)
			(stroke
				(width 0.1)
				(type default)
			)
			(layer "F.Fab")
		)
		(fp_line
			(start -1.549908 1.549908)
			(end -1.549908 -1.549908)
			(stroke
				(width 0.1)
				(type default)
			)
			(layer "F.Fab")
		)
		(fp_line
			(start 1.549908 -1.549908)
			(end 1.549908 1.549908)
			(stroke
				(width 0.1)
				(type default)
			)
			(layer "F.Fab")
		)
		(fp_line
			(start 1.549908 1.549908)
			(end -1.549908 1.549908)
			(stroke
				(width 0.1)
				(type default)
			)
			(layer "F.Fab")
		)
		(fp_poly
			(pts
				(xy -2.019808 -1.549908) (xy -1.257808 -1.549908) (xy -1.257808 -1.880108) (xy -2.019808 -1.880108)
			)
			(stroke
				(width 0)
				(type default)
			)
			(fill yes)
			(layer "F.Fab")
		)
		(pad "1" smd rect
			(at -1.500124 -1.249934 270)
			(size 0.2794 0.6096)
			(layers "F.Cu" "F.Mask" "F.Paste")
			(net "P3V3_NIC5")
		)
		(pad "2" smd rect
			(at -1.500124 -0.750062 270)
			(size 0.2794 0.6096)
			(layers "F.Cu" "F.Mask" "F.Paste")
			(net "P3V3_NIC5")
		)
		(pad "3" smd rect
			(at -1.500124 -0.249936 270)
			(size 0.2794 0.6096)
			(layers "F.Cu" "F.Mask" "F.Paste")
			(net "P3V3_NIC5")
		)
		(pad "4" smd rect
			(at -1.500124 0.249936 270)
			(size 0.2794 0.6096)
			(layers "F.Cu" "F.Mask" "F.Paste")
			(net "P3V3_NIC5")
		)
		(pad "5" smd rect
			(at -1.500124 0.750062 270)
			(size 0.2794 0.6096)
			(layers "F.Cu" "F.Mask" "F.Paste")
			(net "P3V3_NIC5")
		)
		(pad "6" smd rect
			(at -1.500124 1.249934 270)
			(size 0.2794 0.6096)
			(layers "F.Cu" "F.Mask" "F.Paste")
			(net "GND")
		)
		(pad "7" smd rect
			(at 1.500124 1.249934 270)
			(size 0.2794 0.6096)
			(layers "F.Cu" "F.Mask" "F.Paste")
			(net "P3V3_NIC5_SS")
		)
		(pad "8" smd rect
			(at 1.500124 0.750062 270)
			(size 0.2794 0.6096)
			(layers "F.Cu" "F.Mask" "F.Paste")
			(net "PWRGD_P3V3_NIC5")
		)
		(pad "9" smd rect
			(at 1.500124 0.249936 270)
			(size 0.2794 0.6096)
			(layers "F.Cu" "F.Mask" "F.Paste")
			(net "P3V3_NIC5_OCP")
		)
		(pad "10" smd rect
			(at 1.500124 -0.249936 270)
			(size 0.2794 0.6096)
			(layers "F.Cu" "F.Mask" "F.Paste")
			(net "P5V_AUX")
		)
		(pad "11" smd rect
			(at 1.500124 -0.750062 270)
			(size 0.2794 0.6096)
			(layers "F.Cu" "F.Mask" "F.Paste")
			(net "HP_NIC5_EN")
		)
		(pad "12" smd rect
			(at 1.500124 -1.249934 270)
			(size 0.2794 0.6096)
			(layers "F.Cu" "F.Mask" "F.Paste")
			(net "P3V3_AUX")
		)
		(pad "13" smd rect
			(at 0 0)
			(size 1.9812 2.7178)
			(layers "F.Cu" "F.Mask" "F.Paste")
			(net "P3V3_AUX")
		)
		(zone
			(layer "F.Cu")
			(hatch none 0.5)
			(connect_pads
				(clearance 0)
			)
			(min_thickness 0.25)
			(keepout
				(tracks not_allowed)
				(vias allowed)
				(pads allowed)
				(copperpour not_allowed)
				(footprints allowed)
			)
			(placement
				(enabled no)
				(sheetname "")
			)
			(fill
				(thermal_gap 0.5)
				(thermal_bridge_width 0.5)
				(island_removal_mode 0)
			)
			(polygon
				(pts
					(xy 328.614278 -122.841258) (xy 328.614278 -122.714258) (xy 328.614278 -119.742458) (xy 328.614278 -119.74195)
					(xy 326.328278 -119.74195) (xy 326.328278 -119.742458) (xy 326.328278 -119.869458) (xy 326.328278 -121.291858)
					(xy 326.429878 -121.291858) (xy 326.429878 -119.869458) (xy 328.512678 -119.869458) (xy 328.512678 -122.714258)
					(xy 326.429878 -122.714258) (xy 326.429878 -121.317258) (xy 326.328278 -121.317258) (xy 326.328278 -122.714258)
					(xy 326.328278 -122.841258) (xy 326.328278 -122.841766) (xy 328.614278 -122.841766)
				)
			)
		)
	)
	(footprint ""
		(layer "F.Cu")
		(at 128.295908 -343.952322 90)
		(property "Reference" "C371"
			(at 0 0 90)
			(layer "F.SilkS")
			(hide yes)
			(effects
				(font
					(size 1.27 1.27)
				)
			)
		)
		(property "Value" ""
			(at 0 0 90)
			(layer "F.Fab")
			(effects
				(font
					(size 1.27 1.27)
				)
			)
		)
		(duplicate_pad_numbers_are_jumpers no)
		(fp_line
			(start 0.299974 -0.150114)
			(end 0.299974 0.150114)
			(stroke
				(width 0.1)
				(type default)
			)
			(layer "F.Fab")
		)
		(fp_line
			(start -0.299974 -0.150114)
			(end 0.299974 -0.150114)
			(stroke
				(width 0.1)
				(type default)
			)
			(layer "F.Fab")
		)
		(fp_line
			(start 0.299974 0.150114)
			(end -0.299974 0.150114)
			(stroke
				(width 0.1)
				(type default)
			)
			(layer "F.Fab")
		)
		(fp_line
			(start -0.299974 0.150114)
			(end -0.299974 -0.150114)
			(stroke
				(width 0.1)
				(type default)
			)
			(layer "F.Fab")
		)
		(pad "1" smd rect
			(at -0.2667 0 90)
			(size 0.3048 0.381)
			(layers "F.Cu" "F.Mask" "F.Paste")
			(net "P5E_PEX1_STN6_TX_DN<96>")
		)
		(pad "2" smd rect
			(at 0.2667 0 90)
			(size 0.3048 0.381)
			(layers "F.Cu" "F.Mask" "F.Paste")
			(net "P5E_PEX1_STN6_TX_C_DN<96>")
		)
	)
	(footprint ""
		(layer "F.Cu")
		(at 207.98409 -289.230816 90)
		(property "Reference" "R3937"
			(at 0 0 90)
			(layer "F.SilkS")
			(hide yes)
			(effects
				(font
					(size 1.27 1.27)
				)
			)
		)
		(property "Value" ""
			(at 0 0 90)
			(layer "F.Fab")
			(effects
				(font
					(size 1.27 1.27)
				)
			)
		)
		(duplicate_pad_numbers_are_jumpers no)
		(fp_line
			(start 0.7874 -0.4064)
			(end 0.7874 0.4064)
			(stroke
				(width 0.1524)
				(type default)
			)
			(layer "F.SilkS")
		)
		(fp_line
			(start -0.7874 -0.4064)
			(end 0.7874 -0.4064)
			(stroke
				(width 0.1524)
				(type default)
			)
			(layer "F.SilkS")
		)
		(fp_line
			(start 0.7874 0.4064)
			(end -0.7874 0.4064)
			(stroke
				(width 0.1524)
				(type default)
			)
			(layer "F.SilkS")
		)
		(fp_line
			(start -0.7874 0.4064)
			(end -0.7874 -0.4064)
			(stroke
				(width 0.1524)
				(type default)
			)
			(layer "F.SilkS")
		)
		(fp_line
			(start -0.12065 -0.305054)
			(end -0.12065 -0.2794)
			(stroke
				(width 0.1)
				(type default)
			)
			(layer "F.Fab")
		)
		(fp_line
			(start -0.67945 -0.305054)
			(end -0.12065 -0.305054)
			(stroke
				(width 0.1)
				(type default)
			)
			(layer "F.Fab")
		)
		(fp_line
			(start 0.67945 -0.3048)
			(end 0.67945 0.3048)
			(stroke
				(width 0.1)
				(type default)
			)
			(layer "F.Fab")
		)
		(fp_line
			(start 0.12065 -0.3048)
			(end 0.67945 -0.3048)
			(stroke
				(width 0.1)
				(type default)
			)
			(layer "F.Fab")
		)
		(fp_line
			(start 0.12065 -0.2794)
			(end 0.12065 -0.3048)
			(stroke
				(width 0.1)
				(type default)
			)
			(layer "F.Fab")
		)
		(fp_line
			(start -0.12065 -0.2794)
			(end 0.12065 -0.2794)
			(stroke
				(width 0.1)
				(type default)
			)
			(layer "F.Fab")
		)
		(fp_line
			(start 0.120396 0.2794)
			(end -0.12065 0.2794)
			(stroke
				(width 0.1)
				(type default)
			)
			(layer "F.Fab")
		)
		(fp_line
			(start -0.12065 0.2794)
			(end -0.12065 0.3048)
			(stroke
				(width 0.1)
				(type default)
			)
			(layer "F.Fab")
		)
		(fp_line
			(start 0.67945 0.3048)
			(end 0.120396 0.3048)
			(stroke
				(width 0.1)
				(type default)
			)
			(layer "F.Fab")
		)
		(fp_line
			(start 0.120396 0.3048)
			(end 0.120396 0.2794)
			(stroke
				(width 0.1)
				(type default)
			)
			(layer "F.Fab")
		)
		(fp_line
			(start -0.12065 0.3048)
			(end -0.67945 0.3048)
			(stroke
				(width 0.1)
				(type default)
			)
			(layer "F.Fab")
		)
		(fp_line
			(start -0.67945 0.3048)
			(end -0.67945 -0.305054)
			(stroke
				(width 0.1)
				(type default)
			)
			(layer "F.Fab")
		)
		(pad "1" smd circle
			(at -0.40005 0 90)
			(size 0 0)
			(layers "F.Cu" "F.Mask" "F.Paste")
			(net "SMB_PEX1_PCA9555_SCL")
		)
		(pad "2" smd circle
			(at 0.40005 0 90)
			(size 0 0)
			(layers "F.Cu" "F.Mask" "F.Paste")
			(net "SMB_PEX1_HOST_LS_SCL")
		)
	)
	(footprint ""
		(layer "F.Cu")
		(at 366.092486 -29.139642 180)
		(property "Reference" "C704"
			(at 0 0 180)
			(layer "F.SilkS")
			(hide yes)
			(effects
				(font
					(size 1.27 1.27)
				)
			)
		)
		(property "Value" ""
			(at 0 0 180)
			(layer "F.Fab")
			(effects
				(font
					(size 1.27 1.27)
				)
			)
		)
		(duplicate_pad_numbers_are_jumpers no)
		(fp_line
			(start 0.299974 0.150114)
			(end -0.299974 0.150114)
			(stroke
				(width 0.1)
				(type default)
			)
			(layer "F.Fab")
		)
		(fp_line
			(start 0.299974 -0.150114)
			(end 0.299974 0.150114)
			(stroke
				(width 0.1)
				(type default)
			)
			(layer "F.Fab")
		)
		(fp_line
			(start -0.299974 0.150114)
			(end -0.299974 -0.150114)
			(stroke
				(width 0.1)
				(type default)
			)
			(layer "F.Fab")
		)
		(fp_line
			(start -0.299974 -0.150114)
			(end 0.299974 -0.150114)
			(stroke
				(width 0.1)
				(type default)
			)
			(layer "F.Fab")
		)
		(pad "1" smd rect
			(at -0.2667 0 180)
			(size 0.3048 0.381)
			(layers "F.Cu" "F.Mask" "F.Paste")
			(net "P5E_PEX3_STN2_TX_DP<44>")
		)
		(pad "2" smd rect
			(at 0.2667 0 180)
			(size 0.3048 0.381)
			(layers "F.Cu" "F.Mask" "F.Paste")
			(net "P5E_PEX3_STN2_TX_C_DP<44>")
		)
	)
	(footprint ""
		(layer "F.Cu")
		(at 465.041488 -529.209762 180)
		(property "Reference" "J33_OTH"
			(at -3.2385 -1.402334 0)
			(unlocked yes)
			(layer "B.SilkS")
			(effects
				(font
					(size 0.7874 0.5842)
					(thickness 0.1524)
				)
				(justify mirror)
			)
		)
		(property "Value" ""
			(at 0 0 180)
			(layer "F.Fab")
			(effects
				(font
					(size 1.27 1.27)
				)
			)
		)
		(duplicate_pad_numbers_are_jumpers no)
		(pad "1" thru_hole circle
			(at 0 0 180)
			(size 0.4572 0.4572)
			(drill 0.2032)
			(layers "*.Cu" "*.Mask")
			(remove_unused_layers no)
			(net "Net_9103")
			(clearance 0.127)
			(thermal_gap 0.127)
			(padstack
				(mode front_inner_back)
				(layer "Inner"
					(shape circle)
					(size 0.4572 0.4572)
					(clearance 0.127)
				)
				(layer "B.Cu"
					(shape circle)
					(size 0.508 0.508)
					(clearance 0.1016)
				)
			)
		)
	)
)
